(kicad_pcb
	(version 20260206)
	(generator "pcbnew")
	(generator_version "10.0")
	(general
		(thickness 1.6)
		(legacy_teardrops no)
	)
	(paper "A4")
	(title_block
		(title "Wiwynn_Tioga_Pass_MB.brd")
		(comment 1 "Tioga Pass / footprints 609-617 of 4770")
	)
	(layers
		(0 "F.Cu" signal "TOP")
		(4 "In1.Cu" signal "L2GND")
		(6 "In2.Cu" signal "L3")
		(8 "In3.Cu" signal "L4GND")
		(10 "In4.Cu" signal "L5")
		(12 "In5.Cu" signal "L6GND")
		(14 "In6.Cu" signal "L7VCC")
		(16 "In7.Cu" signal "L8VCC")
		(18 "In8.Cu" signal "L9GND")
		(20 "In9.Cu" signal "L10")
		(22 "In10.Cu" signal "L11GND")
		(24 "In11.Cu" signal "L12")
		(26 "In12.Cu" signal "L13GND")
		(2 "B.Cu" signal "BOTTOM")
		(9 "F.Adhes" user "F.Adhesive")
		(11 "B.Adhes" user "B.Adhesive")
		(13 "F.Paste" user "Package Geometry/Pastemask Top")
		(15 "B.Paste" user "Package Geometry/Pastemask Bottom")
		(5 "F.SilkS" user "Ref Des/Silkscreen Top")
		(7 "B.SilkS" user "Ref Des/Silkscreen Bottom")
		(1 "F.Mask" user "Board Geometry/Soldermask Top")
		(3 "B.Mask" user "Board Geometry/Soldermask Bottom")
		(17 "Dwgs.User" user "User.Drawings")
		(19 "Cmts.User" user "User.Comments")
		(21 "Eco1.User" user "User.Eco1")
		(23 "Eco2.User" user "User.Eco2")
		(25 "Edge.Cuts" user "Board Geometry/Outline")
		(27 "Margin" user)
		(31 "F.CrtYd" user "Package Geometry/Place Bound Top")
		(29 "B.CrtYd" user "Package Geometry/Place Bound Bottom")
		(35 "F.Fab" user "Ref Des/Assembly Top")
		(33 "B.Fab" user "Ref Des/Assembly Bottom")
	)
	(footprint ""
		(layer "F.Cu")
		(at 281.178 -74.93 90)
		(property "Reference" "R6D7"
			(at 0 0 90)
			(layer "F.SilkS")
			(hide yes)
			(effects
				(font
					(size 1.27 1.27)
				)
			)
		)
		(property "Value" ""
			(at 0 0 90)
			(layer "F.Fab")
			(effects
				(font
					(size 1.27 1.27)
				)
			)
		)
		(duplicate_pad_numbers_are_jumpers no)
		(fp_rect
			(start -0.2794 -0.1016)
			(end 0.2794 0.9906)
			(stroke
				(width 0)
				(type default)
			)
			(fill no)
			(layer "F.CrtYd")
		)
		(fp_line
			(start 0.2794 -0.1016)
			(end -0.2794 -0.1016)
			(stroke
				(width 0.1)
				(type default)
			)
			(layer "F.Fab")
		)
		(fp_line
			(start -0.2794 -0.1016)
			(end -0.2794 0.9906)
			(stroke
				(width 0.1)
				(type default)
			)
			(layer "F.Fab")
		)
		(fp_line
			(start 0.2794 0.9906)
			(end 0.2794 -0.1016)
			(stroke
				(width 0.1)
				(type default)
			)
			(layer "F.Fab")
		)
		(fp_line
			(start -0.2794 0.9906)
			(end 0.2794 0.9906)
			(stroke
				(width 0.1)
				(type default)
			)
			(layer "F.Fab")
		)
		(pad "1" smd rect
			(at 0 0 90)
			(size 0.508 0.508)
			(layers "F.Cu" "F.Mask" "F.Paste")
			(net "PVCCIO_CPU0")
		)
		(pad "2" smd rect
			(at 0 0.889 90)
			(size 0.508 0.508)
			(layers "F.Cu" "F.Mask" "F.Paste")
			(net "H_CPU0_BMCINIT")
		)
		(zone
			(layer "F.Cu")
			(hatch none 0.5)
			(connect_pads
				(clearance 0)
			)
			(min_thickness 0.25)
			(keepout
				(tracks allowed)
				(vias not_allowed)
				(pads allowed)
				(copperpour not_allowed)
				(footprints allowed)
			)
			(placement
				(enabled no)
				(sheetname "")
			)
			(fill
				(thermal_gap 0.5)
				(thermal_bridge_width 0.5)
				(island_removal_mode 0)
			)
			(polygon
				(pts
					(xy 281.432 -74.676) (xy 281.813 -74.676) (xy 281.813 -75.184) (xy 281.432 -75.184)
				)
			)
		)
		(zone
			(layer "F.Cu")
			(hatch none 0.5)
			(connect_pads
				(clearance 0)
			)
			(min_thickness 0.25)
			(keepout
				(tracks not_allowed)
				(vias allowed)
				(pads allowed)
				(copperpour not_allowed)
				(footprints allowed)
			)
			(placement
				(enabled no)
				(sheetname "")
			)
			(fill
				(thermal_gap 0.5)
				(thermal_bridge_width 0.5)
				(island_removal_mode 0)
			)
			(polygon
				(pts
					(xy 281.432 -74.676) (xy 281.813 -74.676) (xy 281.813 -75.184) (xy 281.432 -75.184)
				)
			)
		)
	)
	(footprint ""
		(layer "F.Cu")
		(at 169.103294 -10.262362 90)
		(property "Reference" "C4G26"
			(at 0 0 90)
			(layer "F.SilkS")
			(hide yes)
			(effects
				(font
					(size 1.27 1.27)
				)
			)
		)
		(property "Value" ""
			(at 0 0 90)
			(layer "F.Fab")
			(effects
				(font
					(size 1.27 1.27)
				)
			)
		)
		(duplicate_pad_numbers_are_jumpers no)
		(fp_rect
			(start 0.4953 1.6002)
			(end -0.4953 -0.2032)
			(stroke
				(width 0)
				(type default)
			)
			(fill no)
			(layer "F.CrtYd")
		)
		(fp_line
			(start 0.4953 -0.2032)
			(end 0.4953 1.6002)
			(stroke
				(width 0.1)
				(type default)
			)
			(layer "F.Fab")
		)
		(fp_line
			(start -0.4953 -0.2032)
			(end 0.4953 -0.2032)
			(stroke
				(width 0.1)
				(type default)
			)
			(layer "F.Fab")
		)
		(fp_line
			(start 0.4953 1.6002)
			(end -0.4953 1.6002)
			(stroke
				(width 0.1)
				(type default)
			)
			(layer "F.Fab")
		)
		(fp_line
			(start -0.4953 1.6002)
			(end -0.4953 -0.2032)
			(stroke
				(width 0.1)
				(type default)
			)
			(layer "F.Fab")
		)
		(pad "1" smd rect
			(at 0 0 90)
			(size 0.762 0.889)
			(layers "F.Cu" "F.Mask" "F.Paste")
			(net "VR_PVPP_GHJ_PHASE")
		)
		(pad "2" smd rect
			(at 0 1.397 90)
			(size 0.762 0.889)
			(layers "F.Cu" "F.Mask" "F.Paste")
			(net "VR_PVPP_GHJ_BOOT_R")
		)
		(zone
			(layer "F.Cu")
			(hatch none 0.5)
			(connect_pads
				(clearance 0)
			)
			(min_thickness 0.25)
			(keepout
				(tracks not_allowed)
				(vias allowed)
				(pads allowed)
				(copperpour not_allowed)
				(footprints allowed)
			)
			(placement
				(enabled no)
				(sheetname "")
			)
			(fill
				(thermal_gap 0.5)
				(thermal_bridge_width 0.5)
				(island_removal_mode 0)
			)
			(polygon
				(pts
					(xy 170.055794 -10.643362) (xy 169.547794 -10.643362) (xy 169.547794 -9.881362) (xy 170.055794 -9.881362)
				)
			)
		)
	)
	(footprint ""
		(layer "F.Cu")
		(at 83.856068 -12.954 -90)
		(property "Reference" "C2G2"
			(at 1.848866 0.752348 270)
			(unlocked yes)
			(layer "F.SilkS")
			(effects
				(font
					(size 1.27 0.9652)
					(thickness 0.1524)
				)
			)
		)
		(property "Value" ""
			(at 0 0 270)
			(layer "F.Fab")
			(effects
				(font
					(size 1.27 1.27)
				)
			)
		)
		(duplicate_pad_numbers_are_jumpers no)
		(fp_rect
			(start -0.500126 1.598422)
			(end 0.500126 -0.201422)
			(stroke
				(width 0)
				(type default)
			)
			(fill no)
			(layer "F.CrtYd")
		)
		(fp_line
			(start -0.500126 1.598422)
			(end -0.500126 -0.201422)
			(stroke
				(width 0.1)
				(type default)
			)
			(layer "F.Fab")
		)
		(fp_line
			(start 0.500126 1.598422)
			(end -0.500126 1.598422)
			(stroke
				(width 0.1)
				(type default)
			)
			(layer "F.Fab")
		)
		(fp_line
			(start -0.500126 -0.201422)
			(end 0.500126 -0.201422)
			(stroke
				(width 0.1)
				(type default)
			)
			(layer "F.Fab")
		)
		(fp_line
			(start 0.500126 -0.201422)
			(end 0.500126 1.598422)
			(stroke
				(width 0.1)
				(type default)
			)
			(layer "F.Fab")
		)
		(pad "1" smd rect
			(at 0 0 180)
			(size 0.889 0.9906)
			(layers "F.Cu" "F.Mask" "F.Paste")
			(net "PVDDQ_GHJ")
		)
		(pad "2" smd rect
			(at 0 1.397 180)
			(size 0.889 0.9906)
			(layers "F.Cu" "F.Mask" "F.Paste")
			(net "GND")
		)
		(zone
			(layer "F.Cu")
			(hatch none 0.5)
			(connect_pads
				(clearance 0)
			)
			(min_thickness 0.25)
			(keepout
				(tracks allowed)
				(vias not_allowed)
				(pads allowed)
				(copperpour not_allowed)
				(footprints allowed)
			)
			(placement
				(enabled no)
				(sheetname "")
			)
			(fill
				(thermal_gap 0.5)
				(thermal_bridge_width 0.5)
				(island_removal_mode 0)
			)
			(polygon
				(pts
					(xy 82.903568 -13.4493) (xy 82.903568 -12.4587) (xy 83.411568 -12.4587) (xy 83.411568 -13.4493)
				)
			)
		)
		(zone
			(layer "F.Cu")
			(hatch none 0.5)
			(connect_pads
				(clearance 0)
			)
			(min_thickness 0.25)
			(keepout
				(tracks not_allowed)
				(vias allowed)
				(pads allowed)
				(copperpour not_allowed)
				(footprints allowed)
			)
			(placement
				(enabled no)
				(sheetname "")
			)
			(fill
				(thermal_gap 0.5)
				(thermal_bridge_width 0.5)
				(island_removal_mode 0)
			)
			(polygon
				(pts
					(xy 82.903568 -13.4493) (xy 82.903568 -12.4587) (xy 83.411568 -12.4587) (xy 83.411568 -13.4493)
				)
			)
		)
	)
	(footprint ""
		(layer "F.Cu")
		(at 473.075 -146.7485)
		(property "Reference" "R9A13"
			(at 0 0 0)
			(layer "F.SilkS")
			(hide yes)
			(effects
				(font
					(size 1.27 1.27)
				)
			)
		)
		(property "Value" ""
			(at 0 0 0)
			(layer "F.Fab")
			(effects
				(font
					(size 1.27 1.27)
				)
			)
		)
		(duplicate_pad_numbers_are_jumpers no)
		(fp_poly
			(pts
				(xy -0.2794 -0.1016) (xy 0.2794 -0.1016) (xy 0.2794 0.9906) (xy -0.2794 0.9906)
			)
			(stroke
				(width 0)
				(type default)
			)
			(fill no)
			(layer "F.CrtYd")
		)
		(fp_line
			(start -0.2794 -0.1016)
			(end -0.2794 0.9906)
			(stroke
				(width 0.1)
				(type default)
			)
			(layer "F.Fab")
		)
		(fp_line
			(start -0.2794 0.9906)
			(end 0.2794 0.9906)
			(stroke
				(width 0.1)
				(type default)
			)
			(layer "F.Fab")
		)
		(fp_line
			(start 0.2794 -0.1016)
			(end -0.2794 -0.1016)
			(stroke
				(width 0.1)
				(type default)
			)
			(layer "F.Fab")
		)
		(fp_line
			(start 0.2794 0.9906)
			(end 0.2794 -0.1016)
			(stroke
				(width 0.1)
				(type default)
			)
			(layer "F.Fab")
		)
		(pad "1" smd rect
			(at 0 0)
			(size 0.508 0.508)
			(layers "F.Cu" "F.Mask" "F.Paste")
			(net "FM_PCH_SATA_RAID_KEY_R")
		)
		(pad "2" smd rect
			(at 0 0.889)
			(size 0.508 0.508)
			(layers "F.Cu" "F.Mask" "F.Paste")
			(net "FM_PCH_SATA_RAID_KEY")
		)
		(zone
			(layer "F.Cu")
			(hatch none 0.5)
			(connect_pads
				(clearance 0)
			)
			(min_thickness 0.25)
			(keepout
				(tracks allowed)
				(vias not_allowed)
				(pads allowed)
				(copperpour not_allowed)
				(footprints allowed)
			)
			(placement
				(enabled no)
				(sheetname "")
			)
			(fill
				(thermal_gap 0.5)
				(thermal_bridge_width 0.5)
				(island_removal_mode 0)
			)
			(polygon
				(pts
					(xy 472.821 -146.4945) (xy 473.329 -146.4945) (xy 473.329 -146.1135) (xy 472.821 -146.1135)
				)
			)
		)
		(zone
			(layer "F.Cu")
			(hatch none 0.5)
			(connect_pads
				(clearance 0)
			)
			(min_thickness 0.25)
			(keepout
				(tracks not_allowed)
				(vias allowed)
				(pads allowed)
				(copperpour not_allowed)
				(footprints allowed)
			)
			(placement
				(enabled no)
				(sheetname "")
			)
			(fill
				(thermal_gap 0.5)
				(thermal_bridge_width 0.5)
				(island_removal_mode 0)
			)
			(polygon
				(pts
					(xy 472.821 -146.1135) (xy 473.329 -146.1135) (xy 473.329 -146.4945) (xy 472.821 -146.4945)
				)
			)
		)
	)
	(footprint ""
		(layer "F.Cu")
		(at 351.028 -28.575 180)
		(property "Reference" "C7F5"
			(at 0 0 180)
			(layer "F.SilkS")
			(hide yes)
			(effects
				(font
					(size 1.27 1.27)
				)
			)
		)
		(property "Value" ""
			(at 0 0 180)
			(layer "F.Fab")
			(effects
				(font
					(size 1.27 1.27)
				)
			)
		)
		(duplicate_pad_numbers_are_jumpers no)
		(fp_poly
			(pts
				(xy -0.7239 -0.2159) (xy 0.7239 -0.2159) (xy 0.7239 1.9939) (xy -0.7239 1.9939)
			)
			(stroke
				(width 0)
				(type default)
			)
			(fill no)
			(layer "F.CrtYd")
		)
		(fp_line
			(start 0.7239 1.9939)
			(end 0.7239 -0.2159)
			(stroke
				(width 0.1)
				(type default)
			)
			(layer "F.Fab")
		)
		(fp_line
			(start 0.7239 -0.2159)
			(end -0.7239 -0.2159)
			(stroke
				(width 0.1)
				(type default)
			)
			(layer "F.Fab")
		)
		(fp_line
			(start -0.7239 1.9939)
			(end 0.7239 1.9939)
			(stroke
				(width 0.1)
				(type default)
			)
			(layer "F.Fab")
		)
		(fp_line
			(start -0.7239 -0.2159)
			(end -0.7239 1.9939)
			(stroke
				(width 0.1)
				(type default)
			)
			(layer "F.Fab")
		)
		(pad "1" smd rect
			(at 0 0 180)
			(size 1.27 1.016)
			(layers "F.Cu" "F.Mask" "F.Paste")
			(net "VR_FET_SW_P12V_STBY_PVPP_ABC")
		)
		(pad "2" smd rect
			(at 0 1.778 180)
			(size 1.27 1.016)
			(layers "F.Cu" "F.Mask" "F.Paste")
			(net "GND")
		)
		(zone
			(layer "F.Cu")
			(hatch none 0.5)
			(connect_pads
				(clearance 0)
			)
			(min_thickness 0.25)
			(keepout
				(tracks not_allowed)
				(vias allowed)
				(pads allowed)
				(copperpour not_allowed)
				(footprints allowed)
			)
			(placement
				(enabled no)
				(sheetname "")
			)
			(fill
				(thermal_gap 0.5)
				(thermal_bridge_width 0.5)
				(island_removal_mode 0)
			)
			(polygon
				(pts
					(xy 351.663 -29.083) (xy 350.393 -29.083) (xy 350.393 -29.845) (xy 351.663 -29.845)
				)
			)
		)
	)
	(footprint ""
		(layer "F.Cu")
		(at 422.5798 -21.4122 180)
		(property "Reference" "R8E19"
			(at 0 0 180)
			(layer "F.SilkS")
			(hide yes)
			(effects
				(font
					(size 1.27 1.27)
				)
			)
		)
		(property "Value" ""
			(at 0 0 180)
			(layer "F.Fab")
			(effects
				(font
					(size 1.27 1.27)
				)
			)
		)
		(duplicate_pad_numbers_are_jumpers no)
		(fp_poly
			(pts
				(xy -0.2794 -0.1016) (xy 0.2794 -0.1016) (xy 0.2794 0.9906) (xy -0.2794 0.9906)
			)
			(stroke
				(width 0)
				(type default)
			)
			(fill no)
			(layer "F.CrtYd")
		)
		(fp_line
			(start 0.2794 0.9906)
			(end 0.2794 -0.1016)
			(stroke
				(width 0.1)
				(type default)
			)
			(layer "F.Fab")
		)
		(fp_line
			(start 0.2794 -0.1016)
			(end -0.2794 -0.1016)
			(stroke
				(width 0.1)
				(type default)
			)
			(layer "F.Fab")
		)
		(fp_line
			(start -0.2794 0.9906)
			(end 0.2794 0.9906)
			(stroke
				(width 0.1)
				(type default)
			)
			(layer "F.Fab")
		)
		(fp_line
			(start -0.2794 -0.1016)
			(end -0.2794 0.9906)
			(stroke
				(width 0.1)
				(type default)
			)
			(layer "F.Fab")
		)
		(pad "1" smd rect
			(at 0 0 180)
			(size 0.508 0.508)
			(layers "F.Cu" "F.Mask" "F.Paste")
			(net "P3V3_STBY")
		)
		(pad "2" smd rect
			(at 0 0.889 180)
			(size 0.508 0.508)
			(layers "F.Cu" "F.Mask" "F.Paste")
			(net "FM_BIOS_TOP_SWAP")
		)
		(zone
			(layer "F.Cu")
			(hatch none 0.5)
			(connect_pads
				(clearance 0)
			)
			(min_thickness 0.25)
			(keepout
				(tracks not_allowed)
				(vias allowed)
				(pads allowed)
				(copperpour not_allowed)
				(footprints allowed)
			)
			(placement
				(enabled no)
				(sheetname "")
			)
			(fill
				(thermal_gap 0.5)
				(thermal_bridge_width 0.5)
				(island_removal_mode 0)
			)
			(polygon
				(pts
					(xy 422.8338 -22.0472) (xy 422.3258 -22.0472) (xy 422.3258 -21.6662) (xy 422.8338 -21.6662)
				)
			)
		)
		(zone
			(layer "F.Cu")
			(hatch none 0.5)
			(connect_pads
				(clearance 0)
			)
			(min_thickness 0.25)
			(keepout
				(tracks allowed)
				(vias not_allowed)
				(pads allowed)
				(copperpour not_allowed)
				(footprints allowed)
			)
			(placement
				(enabled no)
				(sheetname "")
			)
			(fill
				(thermal_gap 0.5)
				(thermal_bridge_width 0.5)
				(island_removal_mode 0)
			)
			(polygon
				(pts
					(xy 422.8338 -21.6662) (xy 422.3258 -21.6662) (xy 422.3258 -22.0472) (xy 422.8338 -22.0472)
				)
			)
		)
	)
	(footprint ""
		(layer "F.Cu")
		(at 423.421048 3.679952 180)
		(property "Reference" "BT8G1"
			(at 0 0 180)
			(layer "F.SilkS")
			(hide yes)
			(effects
				(font
					(size 1.27 1.27)
				)
			)
		)
		(property "Value" ""
			(at 0 0 180)
			(layer "F.Fab")
			(effects
				(font
					(size 1.27 1.27)
				)
			)
		)
		(duplicate_pad_numbers_are_jumpers no)
	)
	(footprint ""
		(layer "F.Cu")
		(at 406.654 -94.474792 90)
		(property "Reference" "C8C5"
			(at 0 0 90)
			(layer "F.SilkS")
			(hide yes)
			(effects
				(font
					(size 1.27 1.27)
				)
			)
		)
		(property "Value" ""
			(at 0 0 90)
			(layer "F.Fab")
			(effects
				(font
					(size 1.27 1.27)
				)
			)
		)
		(duplicate_pad_numbers_are_jumpers no)
		(fp_poly
			(pts
				(xy -0.4953 -0.2032) (xy 0.4953 -0.2032) (xy 0.4953 1.6002) (xy -0.4953 1.6002)
			)
			(stroke
				(width 0)
				(type default)
			)
			(fill no)
			(layer "F.CrtYd")
		)
		(fp_line
			(start 0.4953 -0.2032)
			(end 0.4953 1.6002)
			(stroke
				(width 0.1)
				(type default)
			)
			(layer "F.Fab")
		)
		(fp_line
			(start -0.4953 -0.2032)
			(end 0.4953 -0.2032)
			(stroke
				(width 0.1)
				(type default)
			)
			(layer "F.Fab")
		)
		(fp_line
			(start 0.4953 1.6002)
			(end -0.4953 1.6002)
			(stroke
				(width 0.1)
				(type default)
			)
			(layer "F.Fab")
		)
		(fp_line
			(start -0.4953 1.6002)
			(end -0.4953 -0.2032)
			(stroke
				(width 0.1)
				(type default)
			)
			(layer "F.Fab")
		)
		(pad "1" smd rect
			(at 0 0 90)
			(size 0.762 0.889)
			(layers "F.Cu" "F.Mask" "F.Paste")
			(net "P3V3_STBY")
		)
		(pad "2" smd rect
			(at 0 1.397 90)
			(size 0.762 0.889)
			(layers "F.Cu" "F.Mask" "F.Paste")
			(net "GND")
		)
		(zone
			(layer "F.Cu")
			(hatch none 0.5)
			(connect_pads
				(clearance 0)
			)
			(min_thickness 0.25)
			(keepout
				(tracks not_allowed)
				(vias allowed)
				(pads allowed)
				(copperpour not_allowed)
				(footprints allowed)
			)
			(placement
				(enabled no)
				(sheetname "")
			)
			(fill
				(thermal_gap 0.5)
				(thermal_bridge_width 0.5)
				(island_removal_mode 0)
			)
			(polygon
				(pts
					(xy 407.0985 -94.093792) (xy 407.0985 -94.855792) (xy 407.6065 -94.855792) (xy 407.6065 -94.093792)
				)
			)
		)
	)
	(footprint ""
		(layer "F.Cu")
		(at 31.754826 -85.4837 -90)
		(property "Reference" "C1D32"
			(at 0 0 270)
			(layer "F.SilkS")
			(hide yes)
			(effects
				(font
					(size 1.27 1.27)
				)
			)
		)
		(property "Value" ""
			(at 0 0 270)
			(layer "F.Fab")
			(effects
				(font
					(size 1.27 1.27)
				)
			)
		)
		(duplicate_pad_numbers_are_jumpers no)
		(fp_rect
			(start 0.3048 0.9906)
			(end -0.3048 -0.1016)
			(stroke
				(width 0)
				(type default)
			)
			(fill no)
			(layer "F.CrtYd")
		)
		(fp_line
			(start -0.3048 0.9906)
			(end 0.3048 0.9906)
			(stroke
				(width 0.1)
				(type default)
			)
			(layer "F.Fab")
		)
		(fp_line
			(start 0.3048 0.9906)
			(end 0.3048 -0.1016)
			(stroke
				(width 0.1)
				(type default)
			)
			(layer "F.Fab")
		)
		(fp_line
			(start -0.3048 -0.1016)
			(end -0.3048 0.9906)
			(stroke
				(width 0.1)
				(type default)
			)
			(layer "F.Fab")
		)
		(fp_line
			(start 0.3048 -0.1016)
			(end -0.3048 -0.1016)
			(stroke
				(width 0.1)
				(type default)
			)
			(layer "F.Fab")
		)
		(pad "1" smd rect
			(at 0 0 270)
			(size 0.508 0.508)
			(layers "F.Cu" "F.Mask" "F.Paste")
			(net "VR_PVCCIN_CPU1_PH5_VCIN")
		)
		(pad "2" smd rect
			(at 0 0.889 270)
			(size 0.508 0.508)
			(layers "F.Cu" "F.Mask" "F.Paste")
			(net "GND")
		)
		(zone
			(layer "F.Cu")
			(hatch none 0.5)
			(connect_pads
				(clearance 0)
			)
			(min_thickness 0.25)
			(keepout
				(tracks allowed)
				(vias not_allowed)
				(pads allowed)
				(copperpour not_allowed)
				(footprints allowed)
			)
			(placement
				(enabled no)
				(sheetname "")
			)
			(fill
				(thermal_gap 0.5)
				(thermal_bridge_width 0.5)
				(island_removal_mode 0)
			)
			(polygon
				(pts
					(xy 31.119826 -85.2297) (xy 31.500826 -85.2297) (xy 31.500826 -85.7377) (xy 31.119826 -85.7377)
				)
			)
		)
		(zone
			(layer "F.Cu")
			(hatch none 0.5)
			(connect_pads
				(clearance 0)
			)
			(min_thickness 0.25)
			(keepout
				(tracks not_allowed)
				(vias allowed)
				(pads allowed)
				(copperpour not_allowed)
				(footprints allowed)
			)
			(placement
				(enabled no)
				(sheetname "")
			)
			(fill
				(thermal_gap 0.5)
				(thermal_bridge_width 0.5)
				(island_removal_mode 0)
			)
			(polygon
				(pts
					(xy 31.119826 -85.2297) (xy 31.500826 -85.2297) (xy 31.500826 -85.7377) (xy 31.119826 -85.7377)
				)
			)
		)
	)
)
